# S9S_MB_2U (Grand Teton) — schematic netlist excerpt (pin names and nets, part order shuffled) for the footprints in the layout excerpt that follows; sources: Cadence DE-HDL packaged netlist, KiCad conversion of 03242023_DA0F0TMBIJ0_F0T_Motherboard_J_brd_V01_OCP.brd

C318  Q_CAP  47UF 4V 20% X6S  pkg C0805  page 78 : A = PVCCIN_CPU1 ; B = GND
R97  Q_RES  240 1% EMPTY  pkg 0402LF  page 126 : A = PVNN_TERM_CPU0 ; B = PU_CPU0_UPI3_AC_COUPLING
C1864  Q_CAP  0.1UF 25V 10% X7R  pkg 0402  page 166 : A = P3V3_AUX ; B = GND

(kicad_pcb
	(version 20260206)
	(generator "pcbnew")
	(generator_version "10.0")
	(general
		(thickness 1.6)
		(legacy_teardrops no)
	)
	(paper "A4")
	(title_block
		(title "03242023_DA0F0TMBIJ0_F0T_Motherboard_J_brd_V01_OCP.brd")
		(comment 1 "Grand Teton / footprints 4818-4820 of 6105")
	)
	(layers
		(0 "F.Cu" signal "TOP")
		(4 "In1.Cu" signal "GND")
		(6 "In2.Cu" signal "IN1")
		(8 "In3.Cu" signal "GND1")
		(10 "In4.Cu" signal "IN2")
		(12 "In5.Cu" signal "GND2")
		(14 "In6.Cu" signal "IN3")
		(16 "In7.Cu" signal "GND3")
		(18 "In8.Cu" signal "VCC")
		(20 "In9.Cu" signal "VCC1")
		(22 "In10.Cu" signal "GND4")
		(24 "In11.Cu" signal "IN4")
		(26 "In12.Cu" signal "GND5")
		(28 "In13.Cu" signal "IN5")
		(30 "In14.Cu" signal "GND6")
		(32 "In15.Cu" signal "IN6")
		(34 "In16.Cu" signal "GND7")
		(2 "B.Cu" signal "BOTTOM")
		(9 "F.Adhes" user "F.Adhesive")
		(11 "B.Adhes" user "B.Adhesive")
		(13 "F.Paste" user "Package Geometry/Pastemask Top")
		(15 "B.Paste" user "Package Geometry/Pastemask Bottom")
		(5 "F.SilkS" user "Ref Des/Silkscreen Top")
		(7 "B.SilkS" user "Ref Des/Silkscreen Bottom")
		(1 "F.Mask" user "Board Geometry/Soldermask Top")
		(3 "B.Mask" user "Board Geometry/Soldermask Bottom")
		(17 "Dwgs.User" user "User.Drawings")
		(19 "Cmts.User" user "User.Comments")
		(21 "Eco1.User" user "User.Eco1")
		(23 "Eco2.User" user "User.Eco2")
		(25 "Edge.Cuts" user "Board Geometry/Outline")
		(27 "Margin" user)
		(31 "F.CrtYd" user "Package Geometry/Place Bound Top")
		(29 "B.CrtYd" user "Package Geometry/Place Bound Bottom")
		(35 "F.Fab" user "Ref Des/Assembly Top")
		(33 "B.Fab" user "Ref Des/Assembly Bottom")
	)
	(footprint ""
		(layer "B.Cu")
		(at 411.172152 -193.08953 -90)
		(property "Reference" "R97"
			(at 0 0 90)
			(layer "B.SilkS")
			(hide yes)
			(effects
				(font
					(size 1.27 1.27)
				)
				(justify mirror)
			)
		)
		(property "Value" ""
			(at 0 0 90)
			(layer "B.Fab")
			(effects
				(font
					(size 1.27 1.27)
				)
				(justify mirror)
			)
		)
		(duplicate_pad_numbers_are_jumpers no)
		(fp_line
			(start -0.7874 0.4064)
			(end 0.7874 0.4064)
			(stroke
				(width 0.1524)
				(type default)
			)
			(layer "B.SilkS")
		)
		(fp_line
			(start 0.7874 0.4064)
			(end 0.7874 -0.4064)
			(stroke
				(width 0.1524)
				(type default)
			)
			(layer "B.SilkS")
		)
		(fp_line
			(start -0.7874 -0.4064)
			(end -0.7874 0.4064)
			(stroke
				(width 0.1524)
				(type default)
			)
			(layer "B.SilkS")
		)
		(fp_line
			(start 0.7874 -0.4064)
			(end -0.7874 -0.4064)
			(stroke
				(width 0.1524)
				(type default)
			)
			(layer "B.SilkS")
		)
		(fp_line
			(start -0.67945 0.3048)
			(end -0.120396 0.3048)
			(stroke
				(width 0.1)
				(type default)
			)
			(layer "B.Fab")
		)
		(fp_line
			(start -0.120396 0.3048)
			(end -0.120396 0.2794)
			(stroke
				(width 0.1)
				(type default)
			)
			(layer "B.Fab")
		)
		(fp_line
			(start 0.12065 0.3048)
			(end 0.67945 0.3048)
			(stroke
				(width 0.1)
				(type default)
			)
			(layer "B.Fab")
		)
		(fp_line
			(start 0.67945 0.3048)
			(end 0.67945 -0.305054)
			(stroke
				(width 0.1)
				(type default)
			)
			(layer "B.Fab")
		)
		(fp_line
			(start -0.120396 0.2794)
			(end 0.12065 0.2794)
			(stroke
				(width 0.1)
				(type default)
			)
			(layer "B.Fab")
		)
		(fp_line
			(start 0.12065 0.2794)
			(end 0.12065 0.3048)
			(stroke
				(width 0.1)
				(type default)
			)
			(layer "B.Fab")
		)
		(fp_line
			(start -0.12065 -0.2794)
			(end -0.12065 -0.3048)
			(stroke
				(width 0.1)
				(type default)
			)
			(layer "B.Fab")
		)
		(fp_line
			(start 0.12065 -0.2794)
			(end -0.12065 -0.2794)
			(stroke
				(width 0.1)
				(type default)
			)
			(layer "B.Fab")
		)
		(fp_line
			(start -0.67945 -0.3048)
			(end -0.67945 0.3048)
			(stroke
				(width 0.1)
				(type default)
			)
			(layer "B.Fab")
		)
		(fp_line
			(start -0.12065 -0.3048)
			(end -0.67945 -0.3048)
			(stroke
				(width 0.1)
				(type default)
			)
			(layer "B.Fab")
		)
		(fp_line
			(start 0.12065 -0.305054)
			(end 0.12065 -0.2794)
			(stroke
				(width 0.1)
				(type default)
			)
			(layer "B.Fab")
		)
		(fp_line
			(start 0.67945 -0.305054)
			(end 0.12065 -0.305054)
			(stroke
				(width 0.1)
				(type default)
			)
			(layer "B.Fab")
		)
		(pad "1" smd circle
			(at 0.40005 0 90)
			(size 0 0)
			(layers "B.Cu" "B.Mask" "B.Paste")
			(net "PVNN_TERM_CPU0")
		)
		(pad "2" smd circle
			(at -0.40005 0 90)
			(size 0 0)
			(layers "B.Cu" "B.Mask" "B.Paste")
			(net "PU_CPU0_UPI3_AC_COUPLING")
		)
	)
	(footprint ""
		(layer "B.Cu")
		(at 107.457494 -244.82044 -90)
		(property "Reference" "C318"
			(at 0 0 90)
			(layer "B.SilkS")
			(hide yes)
			(effects
				(font
					(size 1.27 1.27)
				)
				(justify mirror)
			)
		)
		(property "Value" ""
			(at 0 0 90)
			(layer "B.Fab")
			(effects
				(font
					(size 1.27 1.27)
				)
				(justify mirror)
			)
		)
		(duplicate_pad_numbers_are_jumpers no)
		(fp_line
			(start -1.524 0.762)
			(end 1.524 0.762)
			(stroke
				(width 0.1524)
				(type default)
			)
			(layer "B.SilkS")
		)
		(fp_line
			(start 1.524 0.762)
			(end 1.524 -0.762)
			(stroke
				(width 0.1524)
				(type default)
			)
			(layer "B.SilkS")
		)
		(fp_line
			(start -1.524 -0.762)
			(end -1.524 0.762)
			(stroke
				(width 0.1524)
				(type default)
			)
			(layer "B.SilkS")
		)
		(fp_line
			(start 1.524 -0.762)
			(end -1.524 -0.762)
			(stroke
				(width 0.1524)
				(type default)
			)
			(layer "B.SilkS")
		)
		(fp_line
			(start -1.1049 0.724916)
			(end -1.1049 -0.724916)
			(stroke
				(width 0.1)
				(type default)
			)
			(layer "B.Fab")
		)
		(fp_line
			(start 1.1049 0.724916)
			(end -1.1049 0.724916)
			(stroke
				(width 0.1)
				(type default)
			)
			(layer "B.Fab")
		)
		(fp_line
			(start -1.1049 -0.724916)
			(end 1.1049 -0.724916)
			(stroke
				(width 0.1)
				(type default)
			)
			(layer "B.Fab")
		)
		(fp_line
			(start 1.1049 -0.724916)
			(end 1.1049 0.724916)
			(stroke
				(width 0.1)
				(type default)
			)
			(layer "B.Fab")
		)
		(pad "1" smd rect
			(at 0.889 0 270)
			(size 1.016 1.27)
			(layers "B.Cu" "B.Mask" "B.Paste")
			(net "PVCCIN_CPU1")
		)
		(pad "2" smd rect
			(at -0.889 0 270)
			(size 1.016 1.27)
			(layers "B.Cu" "B.Mask" "B.Paste")
			(net "GND")
		)
	)
	(footprint ""
		(layer "B.Cu")
		(at 24.0538 -391.483088 90)
		(property "Reference" "C1864"
			(at 0 0 90)
			(layer "B.SilkS")
			(hide yes)
			(effects
				(font
					(size 1.27 1.27)
				)
				(justify mirror)
			)
		)
		(property "Value" ""
			(at 0 0 90)
			(layer "B.Fab")
			(effects
				(font
					(size 1.27 1.27)
				)
				(justify mirror)
			)
		)
		(duplicate_pad_numbers_are_jumpers no)
		(fp_line
			(start 0.7874 -0.4064)
			(end -0.7874 -0.4064)
			(stroke
				(width 0.1524)
				(type default)
			)
			(layer "B.SilkS")
		)
		(fp_line
			(start -0.7874 -0.4064)
			(end -0.7874 0.4064)
			(stroke
				(width 0.1524)
				(type default)
			)
			(layer "B.SilkS")
		)
		(fp_line
			(start 0.7874 0.4064)
			(end 0.7874 -0.4064)
			(stroke
				(width 0.1524)
				(type default)
			)
			(layer "B.SilkS")
		)
		(fp_line
			(start -0.7874 0.4064)
			(end 0.7874 0.4064)
			(stroke
				(width 0.1524)
				(type default)
			)
			(layer "B.SilkS")
		)
		(fp_line
			(start 0.67945 -0.305054)
			(end 0.12065 -0.305054)
			(stroke
				(width 0.1)
				(type default)
			)
			(layer "B.Fab")
		)
		(fp_line
			(start 0.12065 -0.305054)
			(end 0.12065 -0.2794)
			(stroke
				(width 0.1)
				(type default)
			)
			(layer "B.Fab")
		)
		(fp_line
			(start -0.12065 -0.3048)
			(end -0.67945 -0.3048)
			(stroke
				(width 0.1)
				(type default)
			)
			(layer "B.Fab")
		)
		(fp_line
			(start -0.67945 -0.3048)
			(end -0.67945 0.3048)
			(stroke
				(width 0.1)
				(type default)
			)
			(layer "B.Fab")
		)
		(fp_line
			(start 0.12065 -0.2794)
			(end -0.12065 -0.2794)
			(stroke
				(width 0.1)
				(type default)
			)
			(layer "B.Fab")
		)
		(fp_line
			(start -0.12065 -0.2794)
			(end -0.12065 -0.3048)
			(stroke
				(width 0.1)
				(type default)
			)
			(layer "B.Fab")
		)
		(fp_line
			(start 0.12065 0.2794)
			(end 0.12065 0.3048)
			(stroke
				(width 0.1)
				(type default)
			)
			(layer "B.Fab")
		)
		(fp_line
			(start -0.120396 0.2794)
			(end 0.12065 0.2794)
			(stroke
				(width 0.1)
				(type default)
			)
			(layer "B.Fab")
		)
		(fp_line
			(start 0.67945 0.3048)
			(end 0.67945 -0.305054)
			(stroke
				(width 0.1)
				(type default)
			)
			(layer "B.Fab")
		)
		(fp_line
			(start 0.12065 0.3048)
			(end 0.67945 0.3048)
			(stroke
				(width 0.1)
				(type default)
			)
			(layer "B.Fab")
		)
		(fp_line
			(start -0.120396 0.3048)
			(end -0.120396 0.2794)
			(stroke
				(width 0.1)
				(type default)
			)
			(layer "B.Fab")
		)
		(fp_line
			(start -0.67945 0.3048)
			(end -0.120396 0.3048)
			(stroke
				(width 0.1)
				(type default)
			)
			(layer "B.Fab")
		)
		(pad "1" smd circle
			(at 0.40005 0 270)
			(size 0 0)
			(layers "B.Cu" "B.Mask" "B.Paste")
			(net "P3V3_AUX")
		)
		(pad "2" smd circle
			(at -0.40005 0 270)
			(size 0 0)
			(layers "B.Cu" "B.Mask" "B.Paste")
			(net "GND")
		)
	)
)
